(kicad_pcb
	(version 20241229)
	(generator "pcbnew")
	(generator_version "9.0")
	(general
		(thickness 1.292)
		(legacy_teardrops no)
	)
	(paper "A4")
	(title_block
		(title "LPDDR5 Testbed")
		(date "2023-12-19")
		(rev "1.0.0")
		(comment 9 "footprints 75-82 of 160")
	)
	(layers
		(0 "F.Cu" signal)
		(4 "In1.Cu" power)
		(6 "In2.Cu" power)
		(8 "In3.Cu" signal)
		(10 "In4.Cu" signal)
		(2 "B.Cu" signal)
		(9 "F.Adhes" user "F.Adhesive")
		(11 "B.Adhes" user "B.Adhesive")
		(13 "F.Paste" user)
		(15 "B.Paste" user)
		(5 "F.SilkS" user "F.Silkscreen")
		(7 "B.SilkS" user "B.Silkscreen")
		(1 "F.Mask" user)
		(3 "B.Mask" user)
		(17 "Dwgs.User" user "User.Drawings")
		(19 "Cmts.User" user "User.Comments")
		(21 "Eco1.User" user "User.Eco1")
		(23 "Eco2.User" user "User.Eco2")
		(25 "Edge.Cuts" user)
		(27 "Margin" user)
		(31 "F.CrtYd" user "F.Courtyard")
		(29 "B.CrtYd" user "B.Courtyard")
		(35 "F.Fab" user)
		(33 "B.Fab" user)
	)
	(footprint "antmicro-footprints:C_0402_1005Metric"
		(layer "F.Cu")
		(at 164.475 70.65 180)
		(descr "Capacitor SMD 0402")
		(tags "capacitor SMD 0402")
		(property "Reference" "C20"
			(at -1.125 -2.45 0)
			(unlocked yes)
			(layer "F.SilkS")
			(effects
				(font
					(size 0.7 0.7)
					(thickness 0.15)
				)
				(justify right bottom)
			)
		)
		(property "Value" "C_4u7_0402"
			(at -1.022927 2.155213 0)
			(layer "F.Fab")
			(effects
				(font
					(size 0.7 0.7)
					(thickness 0.15)
				)
				(justify right bottom)
			)
		)
		(property "Author" "Antmicro"
			(at 328.95 141.3 0)
			(layer "F.Fab")
			(hide yes)
			(effects
				(font
					(size 1 1)
					(thickness 0.15)
				)
			)
		)
		(property "Dielectric" ""
			(at 328.95 141.3 0)
			(layer "F.Fab")
			(hide yes)
			(effects
				(font
					(size 1 1)
					(thickness 0.15)
				)
			)
		)
		(property "License" "Apache-2.0"
			(at 328.95 141.3 0)
			(layer "F.Fab")
			(hide yes)
			(effects
				(font
					(size 1 1)
					(thickness 0.15)
				)
			)
		)
		(property "MPN" "GRM155R61A475MEAAD"
			(at 328.95 141.3 0)
			(layer "F.Fab")
			(hide yes)
			(effects
				(font
					(size 1 1)
					(thickness 0.15)
				)
			)
		)
		(property "Manufacturer" "Murata"
			(at 328.95 141.3 0)
			(layer "F.Fab")
			(hide yes)
			(effects
				(font
					(size 1 1)
					(thickness 0.15)
				)
			)
		)
		(property "Val" "4u7"
			(at 328.95 141.3 0)
			(layer "F.Fab")
			(hide yes)
			(effects
				(font
					(size 1 1)
					(thickness 0.15)
				)
			)
		)
		(property "Voltage" ""
			(at 328.95 141.3 0)
			(layer "F.Fab")
			(hide yes)
			(effects
				(font
					(size 1 1)
					(thickness 0.15)
				)
			)
		)
		(sheetname "Power supply")
		(sheetfile "power_supply.kicad_sch")
		(attr smd)
		(fp_rect
			(start -0.9659 -0.481258)
			(end 0.9649 0.458742)
			(stroke
				(width 0.05)
				(type solid)
			)
			(fill no)
			(layer "F.CrtYd")
		)
		(fp_line
			(start 0.499 0.248)
			(end -0.499 0.248)
			(stroke
				(width 0.15)
				(type solid)
			)
			(layer "F.Fab")
		)
		(fp_line
			(start 0.499 -0.25)
			(end 0.499 0.248)
			(stroke
				(width 0.15)
				(type solid)
			)
			(layer "F.Fab")
		)
		(fp_line
			(start -0.499 0.248)
			(end -0.499 -0.25)
			(stroke
				(width 0.15)
				(type solid)
			)
			(layer "F.Fab")
		)
		(fp_line
			(start -0.499 -0.25)
			(end 0.499 -0.25)
			(stroke
				(width 0.15)
				(type solid)
			)
			(layer "F.Fab")
		)
		(pad "1" smd roundrect
			(at -0.484 0 180)
			(size 0.59 0.64)
			(layers "F.Cu" "F.Mask" "F.Paste")
			(roundrect_rratio 0.25)
			(net 14 "GND")
			(pintype "passive")
		)
		(pad "2" smd roundrect
			(at 0.484 0 180)
			(size 0.59 0.64)
			(layers "F.Cu" "F.Mask" "F.Paste")
			(roundrect_rratio 0.25)
			(net 11 "/Power supply/VOUT")
			(pintype "passive")
		)
	)
	(footprint "antmicro-footprints:C_0402_1005Metric"
		(layer "F.Cu")
		(at 135.875 88.275 180)
		(descr "Capacitor SMD 0402")
		(tags "capacitor SMD 0402")
		(property "Reference" "C67"
			(at -3.325 -0.25 0)
			(unlocked yes)
			(layer "F.SilkS")
			(effects
				(font
					(size 0.7 0.7)
					(thickness 0.15)
				)
				(justify right bottom)
			)
		)
		(property "Value" "C_4u7_0402"
			(at -1.022927 2.155213 0)
			(layer "F.Fab")
			(effects
				(font
					(size 0.7 0.7)
					(thickness 0.15)
				)
				(justify right bottom)
			)
		)
		(property "Author" "Antmicro"
			(at 271.75 176.55 0)
			(layer "F.Fab")
			(hide yes)
			(effects
				(font
					(size 1 1)
					(thickness 0.15)
				)
			)
		)
		(property "Dielectric" ""
			(at 271.75 176.55 0)
			(layer "F.Fab")
			(hide yes)
			(effects
				(font
					(size 1 1)
					(thickness 0.15)
				)
			)
		)
		(property "License" "Apache-2.0"
			(at 271.75 176.55 0)
			(layer "F.Fab")
			(hide yes)
			(effects
				(font
					(size 1 1)
					(thickness 0.15)
				)
			)
		)
		(property "MPN" "GRM155R61A475MEAAD"
			(at 271.75 176.55 0)
			(layer "F.Fab")
			(hide yes)
			(effects
				(font
					(size 1 1)
					(thickness 0.15)
				)
			)
		)
		(property "Manufacturer" "Murata"
			(at 271.75 176.55 0)
			(layer "F.Fab")
			(hide yes)
			(effects
				(font
					(size 1 1)
					(thickness 0.15)
				)
			)
		)
		(property "Val" "4u7"
			(at 271.75 176.55 0)
			(layer "F.Fab")
			(hide yes)
			(effects
				(font
					(size 1 1)
					(thickness 0.15)
				)
			)
		)
		(property "Voltage" ""
			(at 271.75 176.55 0)
			(layer "F.Fab")
			(hide yes)
			(effects
				(font
					(size 1 1)
					(thickness 0.15)
				)
			)
		)
		(sheetname "LPDDR5")
		(sheetfile "lpddr5.kicad_sch")
		(attr smd)
		(fp_rect
			(start -0.9659 -0.481258)
			(end 0.9649 0.458742)
			(stroke
				(width 0.05)
				(type solid)
			)
			(fill no)
			(layer "F.CrtYd")
		)
		(fp_line
			(start 0.499 0.248)
			(end -0.499 0.248)
			(stroke
				(width 0.15)
				(type solid)
			)
			(layer "F.Fab")
		)
		(fp_line
			(start 0.499 -0.25)
			(end 0.499 0.248)
			(stroke
				(width 0.15)
				(type solid)
			)
			(layer "F.Fab")
		)
		(fp_line
			(start -0.499 0.248)
			(end -0.499 -0.25)
			(stroke
				(width 0.15)
				(type solid)
			)
			(layer "F.Fab")
		)
		(fp_line
			(start -0.499 -0.25)
			(end 0.499 -0.25)
			(stroke
				(width 0.15)
				(type solid)
			)
			(layer "F.Fab")
		)
		(pad "1" smd roundrect
			(at -0.484 0 180)
			(size 0.59 0.64)
			(layers "F.Cu" "F.Mask" "F.Paste")
			(roundrect_rratio 0.25)
			(net 14 "GND")
			(pintype "passive")
		)
		(pad "2" smd roundrect
			(at 0.484 0 180)
			(size 0.59 0.64)
			(layers "F.Cu" "F.Mask" "F.Paste")
			(roundrect_rratio 0.25)
			(net 13 "+1V05")
			(pintype "passive")
		)
	)
	(footprint "antmicro-footprints:TP_SMD_0.75mm"
		(layer "F.Cu")
		(at 168.068 68.457 90)
		(property "Reference" "TP1"
			(at -1.443 1.332 90)
			(unlocked yes)
			(layer "F.SilkS")
			(effects
				(font
					(size 0.7 0.7)
					(thickness 0.15)
				)
				(justify left bottom)
			)
		)
		(property "Value" "TP_0.75mm_SMD"
			(at 0 1.2 90)
			(layer "F.Fab")
			(effects
				(font
					(size 0.7 0.7)
					(thickness 0.15)
				)
				(justify left bottom)
			)
		)
		(property "Author" "Antmicro"
			(at 236.525 -99.611 0)
			(layer "F.Fab")
			(hide yes)
			(effects
				(font
					(size 1 1)
					(thickness 0.15)
				)
			)
		)
		(property "License" "Apache-2.0"
			(at 236.525 -99.611 0)
			(layer "F.Fab")
			(hide yes)
			(effects
				(font
					(size 1 1)
					(thickness 0.15)
				)
			)
		)
		(property "MPN" ""
			(at 236.525 -99.611 0)
			(layer "F.Fab")
			(hide yes)
			(effects
				(font
					(size 1 1)
					(thickness 0.15)
				)
			)
		)
		(property "Manufacturer" ""
			(at 236.525 -99.611 0)
			(layer "F.Fab")
			(hide yes)
			(effects
				(font
					(size 1 1)
					(thickness 0.15)
				)
			)
		)
		(sheetname "Power supply")
		(sheetfile "power_supply.kicad_sch")
		(attr exclude_from_pos_files)
		(pad "1" smd circle
			(at 0 0 90)
			(size 0.75 0.75)
			(layers "F.Cu" "F.Mask")
			(net 69 "Net-(R32-Pad2)")
			(pinfunction "1")
			(pintype "passive")
		)
	)
	(footprint "antmicro-footprints:R_0402_1005Metric"
		(layer "F.Cu")
		(at 100.775 66.225 90)
		(descr "Resistor SMD 0402")
		(tags "resistor SMD 0402")
		(property "Reference" "R33"
			(at 0.825 0.425 90)
			(unlocked yes)
			(layer "F.SilkS")
			(effects
				(font
					(size 0.7 0.7)
					(thickness 0.15)
				)
				(justify left bottom)
			)
		)
		(property "Value" "R_100k_0402"
			(at -1.011843 1.772047 90)
			(layer "F.Fab")
			(effects
				(font
					(size 0.7 0.7)
					(thickness 0.15)
				)
				(justify left bottom)
			)
		)
		(property "Author" "Antmicro"
			(at 167 -34.55 0)
			(layer "F.Fab")
			(hide yes)
			(effects
				(font
					(size 1 1)
					(thickness 0.15)
				)
			)
		)
		(property "License" "Apache-2.0"
			(at 167 -34.55 0)
			(layer "F.Fab")
			(hide yes)
			(effects
				(font
					(size 1 1)
					(thickness 0.15)
				)
			)
		)
		(property "MPN" "CR0402-FX-1003GLF"
			(at 167 -34.55 0)
			(layer "F.Fab")
			(hide yes)
			(effects
				(font
					(size 1 1)
					(thickness 0.15)
				)
			)
		)
		(property "Manufacturer" "Bourns"
			(at 167 -34.55 0)
			(layer "F.Fab")
			(hide yes)
			(effects
				(font
					(size 1 1)
					(thickness 0.15)
				)
			)
		)
		(property "Tolerance" "1%"
			(at 167 -34.55 0)
			(layer "F.Fab")
			(hide yes)
			(effects
				(font
					(size 1 1)
					(thickness 0.15)
				)
			)
		)
		(property "Val" "100k"
			(at 167 -34.55 0)
			(layer "F.Fab")
			(hide yes)
			(effects
				(font
					(size 1 1)
					(thickness 0.15)
				)
			)
		)
		(sheetname "Power supply")
		(sheetfile "power_supply.kicad_sch")
		(attr smd)
		(fp_rect
			(start -0.93 -0.47)
			(end 0.93 0.47)
			(stroke
				(width 0.05)
				(type solid)
			)
			(fill no)
			(layer "F.CrtYd")
		)
		(fp_rect
			(start -0.5 -0.25)
			(end 0.5 0.25)
			(stroke
				(width 0.15)
				(type solid)
			)
			(fill no)
			(layer "F.Fab")
		)
		(pad "1" smd roundrect
			(at -0.485 0 90)
			(size 0.59 0.64)
			(layers "F.Cu" "F.Mask" "F.Paste")
			(roundrect_rratio 0.25)
			(net 70 "/Power supply/FB1")
			(pintype "passive")
		)
		(pad "2" smd roundrect
			(at 0.485 0 90)
			(size 0.59 0.64)
			(layers "F.Cu" "F.Mask" "F.Paste")
			(roundrect_rratio 0.25)
			(net 7 "/Power supply/VOUT1")
			(pintype "passive")
		)
	)
	(footprint "antmicro-footprints:R_0402_1005Metric"
		(layer "F.Cu")
		(at 107.125 93.775 90)
		(descr "Resistor SMD 0402")
		(tags "resistor SMD 0402")
		(property "Reference" "R20"
			(at -3.025 0.375 90)
			(unlocked yes)
			(layer "F.SilkS")
			(effects
				(font
					(size 0.7 0.7)
					(thickness 0.15)
				)
				(justify left bottom)
			)
		)
		(property "Value" "R_100R_0402"
			(at -1.011843 1.772047 90)
			(layer "F.Fab")
			(effects
				(font
					(size 0.7 0.7)
					(thickness 0.15)
				)
				(justify left bottom)
			)
		)
		(property "Author" "Antmicro"
			(at 200.9 -13.35 0)
			(layer "F.Fab")
			(hide yes)
			(effects
				(font
					(size 1 1)
					(thickness 0.15)
				)
			)
		)
		(property "License" "Apache-2.0"
			(at 200.9 -13.35 0)
			(layer "F.Fab")
			(hide yes)
			(effects
				(font
					(size 1 1)
					(thickness 0.15)
				)
			)
		)
		(property "MPN" "CR0402-FX-1000GLF"
			(at 200.9 -13.35 0)
			(layer "F.Fab")
			(hide yes)
			(effects
				(font
					(size 1 1)
					(thickness 0.15)
				)
			)
		)
		(property "Manufacturer" "Bourns"
			(at 200.9 -13.35 0)
			(layer "F.Fab")
			(hide yes)
			(effects
				(font
					(size 1 1)
					(thickness 0.15)
				)
			)
		)
		(property "Tolerance" "1%"
			(at 200.9 -13.35 0)
			(layer "F.Fab")
			(hide yes)
			(effects
				(font
					(size 1 1)
					(thickness 0.15)
				)
			)
		)
		(property "Val" "100R"
			(at 200.9 -13.35 0)
			(layer "F.Fab")
			(hide yes)
			(effects
				(font
					(size 1 1)
					(thickness 0.15)
				)
			)
		)
		(sheetname "Translators")
		(sheetfile "translators.kicad_sch")
		(attr smd)
		(fp_rect
			(start -0.93 -0.47)
			(end 0.93 0.47)
			(stroke
				(width 0.05)
				(type solid)
			)
			(fill no)
			(layer "F.CrtYd")
		)
		(fp_rect
			(start -0.5 -0.25)
			(end 0.5 0.25)
			(stroke
				(width 0.15)
				(type solid)
			)
			(fill no)
			(layer "F.Fab")
		)
		(pad "1" smd roundrect
			(at -0.485 0 90)
			(size 0.59 0.64)
			(layers "F.Cu" "F.Mask" "F.Paste")
			(roundrect_rratio 0.25)
			(net 118 "/SODIMM/LPDDR5_IN_A.DMI1")
			(pintype "passive")
		)
		(pad "2" smd roundrect
			(at 0.485 0 90)
			(size 0.59 0.64)
			(layers "F.Cu" "F.Mask" "F.Paste")
			(roundrect_rratio 0.25)
			(net 190 "/LPDDR5/LPDDR5_A.DMI1")
			(pintype "passive")
		)
	)
	(footprint "antmicro-footprints:R_0402_1005Metric"
		(layer "F.Cu")
		(at 139.75 93.85 90)
		(descr "Resistor SMD 0402")
		(tags "resistor SMD 0402")
		(property "Reference" "R89"
			(at 1.25 0.25 90)
			(unlocked yes)
			(layer "F.SilkS")
			(effects
				(font
					(size 0.7 0.7)
					(thickness 0.15)
				)
				(justify left bottom)
			)
		)
		(property "Value" "R_100R_0402"
			(at -1.011843 1.772047 90)
			(layer "F.Fab")
			(effects
				(font
					(size 0.7 0.7)
					(thickness 0.15)
				)
				(justify left bottom)
			)
		)
		(property "Author" "Antmicro"
			(at 233.6 -45.9 0)
			(layer "F.Fab")
			(hide yes)
			(effects
				(font
					(size 1 1)
					(thickness 0.15)
				)
			)
		)
		(property "License" "Apache-2.0"
			(at 233.6 -45.9 0)
			(layer "F.Fab")
			(hide yes)
			(effects
				(font
					(size 1 1)
					(thickness 0.15)
				)
			)
		)
		(property "MPN" "CR0402-FX-1000GLF"
			(at 233.6 -45.9 0)
			(layer "F.Fab")
			(hide yes)
			(effects
				(font
					(size 1 1)
					(thickness 0.15)
				)
			)
		)
		(property "Manufacturer" "Bourns"
			(at 233.6 -45.9 0)
			(layer "F.Fab")
			(hide yes)
			(effects
				(font
					(size 1 1)
					(thickness 0.15)
				)
			)
		)
		(property "Tolerance" "1%"
			(at 233.6 -45.9 0)
			(layer "F.Fab")
			(hide yes)
			(effects
				(font
					(size 1 1)
					(thickness 0.15)
				)
			)
		)
		(property "Val" "100R"
			(at 233.6 -45.9 0)
			(layer "F.Fab")
			(hide yes)
			(effects
				(font
					(size 1 1)
					(thickness 0.15)
				)
			)
		)
		(sheetname "Translators1")
		(sheetfile "translators.kicad_sch")
		(attr smd)
		(fp_rect
			(start -0.93 -0.47)
			(end 0.93 0.47)
			(stroke
				(width 0.05)
				(type solid)
			)
			(fill no)
			(layer "F.CrtYd")
		)
		(fp_rect
			(start -0.5 -0.25)
			(end 0.5 0.25)
			(stroke
				(width 0.15)
				(type solid)
			)
			(fill no)
			(layer "F.Fab")
		)
		(pad "1" smd roundrect
			(at -0.485 0 90)
			(size 0.59 0.64)
			(layers "F.Cu" "F.Mask" "F.Paste")
			(roundrect_rratio 0.25)
			(net 152 "/SODIMM/LPDDR5_IN_B.CA6")
			(pintype "passive")
		)
		(pad "2" smd roundrect
			(at 0.485 0 90)
			(size 0.59 0.64)
			(layers "F.Cu" "F.Mask" "F.Paste")
			(roundrect_rratio 0.25)
			(net 100 "/LPDDR5/LPDDR5_B.CA6")
			(pintype "passive")
		)
	)
	(footprint "antmicro-footprints:R_0402_1005Metric"
		(layer "F.Cu")
		(at 112.525 65.625 90)
		(descr "Resistor SMD 0402")
		(tags "resistor SMD 0402")
		(property "Reference" "R35"
			(at -3.075 0.375 90)
			(unlocked yes)
			(layer "F.SilkS")
			(effects
				(font
					(size 0.7 0.7)
					(thickness 0.15)
				)
				(justify left bottom)
			)
		)
		(property "Value" "R_100k_0402"
			(at -1.011843 1.772047 90)
			(layer "F.Fab")
			(effects
				(font
					(size 0.7 0.7)
					(thickness 0.15)
				)
				(justify left bottom)
			)
		)
		(property "Author" "Antmicro"
			(at 178.15 -46.9 0)
			(layer "F.Fab")
			(hide yes)
			(effects
				(font
					(size 1 1)
					(thickness 0.15)
				)
			)
		)
		(property "License" "Apache-2.0"
			(at 178.15 -46.9 0)
			(layer "F.Fab")
			(hide yes)
			(effects
				(font
					(size 1 1)
					(thickness 0.15)
				)
			)
		)
		(property "MPN" "CR0402-FX-1003GLF"
			(at 178.15 -46.9 0)
			(layer "F.Fab")
			(hide yes)
			(effects
				(font
					(size 1 1)
					(thickness 0.15)
				)
			)
		)
		(property "Manufacturer" "Bourns"
			(at 178.15 -46.9 0)
			(layer "F.Fab")
			(hide yes)
			(effects
				(font
					(size 1 1)
					(thickness 0.15)
				)
			)
		)
		(property "Tolerance" "1%"
			(at 178.15 -46.9 0)
			(layer "F.Fab")
			(hide yes)
			(effects
				(font
					(size 1 1)
					(thickness 0.15)
				)
			)
		)
		(property "Val" "100k"
			(at 178.15 -46.9 0)
			(layer "F.Fab")
			(hide yes)
			(effects
				(font
					(size 1 1)
					(thickness 0.15)
				)
			)
		)
		(sheetname "Power supply")
		(sheetfile "power_supply.kicad_sch")
		(attr smd)
		(fp_rect
			(start -0.93 -0.47)
			(end 0.93 0.47)
			(stroke
				(width 0.05)
				(type solid)
			)
			(fill no)
			(layer "F.CrtYd")
		)
		(fp_rect
			(start -0.5 -0.25)
			(end 0.5 0.25)
			(stroke
				(width 0.15)
				(type solid)
			)
			(fill no)
			(layer "F.Fab")
		)
		(pad "1" smd roundrect
			(at -0.485 0 90)
			(size 0.59 0.64)
			(layers "F.Cu" "F.Mask" "F.Paste")
			(roundrect_rratio 0.25)
			(net 71 "/Power supply/FB2")
			(pintype "passive")
		)
		(pad "2" smd roundrect
			(at 0.485 0 90)
			(size 0.59 0.64)
			(layers "F.Cu" "F.Mask" "F.Paste")
			(roundrect_rratio 0.25)
			(net 8 "/Power supply/VOUT2")
			(pintype "passive")
		)
	)
	(footprint "antmicro-footprints:R_0603_1608Metric"
		(layer "F.Cu")
		(at 101.5 72.275 90)
		(descr "Resistor SMD 0603")
		(tags "resistor SMD 0603")
		(property "Reference" "R46"
			(at -3.425 0 90)
			(unlocked yes)
			(layer "F.SilkS")
			(effects
				(font
					(size 0.7 0.7)
					(thickness 0.15)
				)
				(justify left bottom)
			)
		)
		(property "Value" "R_0R_22.4A_0603"
			(at 0 1.6 90)
			(layer "F.Fab")
			(effects
				(font
					(size 0.7 0.7)
					(thickness 0.15)
				)
				(justify left bottom)
			)
		)
		(property "Author" "Antmicro"
			(at 173.775 -29.225 0)
			(layer "F.Fab")
			(hide yes)
			(effects
				(font
					(size 1 1)
					(thickness 0.15)
				)
			)
		)
		(property "License" "Apache-2.0"
			(at 173.775 -29.225 0)
			(layer "F.Fab")
			(hide yes)
			(effects
				(font
					(size 1 1)
					(thickness 0.15)
				)
			)
		)
		(property "MPN" "PMR03EZPJ000"
			(at 173.775 -29.225 0)
			(layer "F.Fab")
			(hide yes)
			(effects
				(font
					(size 1 1)
					(thickness 0.15)
				)
			)
		)
		(property "Manufacturer" "ROHM Semiconductor"
			(at 173.775 -29.225 0)
			(layer "F.Fab")
			(hide yes)
			(effects
				(font
					(size 1 1)
					(thickness 0.15)
				)
			)
		)
		(property "Max. Curr." "22.4A"
			(at 173.775 -29.225 0)
			(layer "F.Fab")
			(hide yes)
			(effects
				(font
					(size 1 1)
					(thickness 0.15)
				)
			)
		)
		(property "Tolerance" "template_tolerance"
			(at 173.775 -29.225 0)
			(layer "F.Fab")
			(hide yes)
			(effects
				(font
					(size 1 1)
					(thickness 0.15)
				)
			)
		)
		(property "Val" "0R"
			(at 173.775 -29.225 0)
			(layer "F.Fab")
			(hide yes)
			(effects
				(font
					(size 1 1)
					(thickness 0.15)
				)
			)
		)
		(sheetname "Power supply")
		(sheetfile "power_supply.kicad_sch")
		(attr smd)
		(fp_line
			(start -0.3 -0.3)
			(end 0.3 -0.3)
			(stroke
				(width 0.15)
				(type solid)
			)
			(layer "F.SilkS")
		)
		(fp_line
			(start -0.3 0.3)
			(end 0.3 0.3)
			(stroke
				(width 0.15)
				(type solid)
			)
			(layer "F.SilkS")
		)
		(fp_rect
			(start -1.25 -0.7)
			(end 1.25 0.7)
			(stroke
				(width 0.05)
				(type solid)
			)
			(fill no)
			(layer "F.CrtYd")
		)
		(fp_rect
			(start -0.8 -0.4)
			(end 0.8 0.4)
			(stroke
				(width 0.15)
				(type solid)
			)
			(fill no)
			(layer "F.Fab")
		)
		(pad "1" smd roundrect
			(at -0.7 0 90)
			(size 0.6 0.8)
			(layers "F.Cu" "F.Mask" "F.Paste")
			(roundrect_rratio 0.2)
			(net 1 "+1V1")
			(pintype "passive")
		)
		(pad "2" smd roundrect
			(at 0.7 0 90)
			(size 0.6 0.8)
			(layers "F.Cu" "F.Mask" "F.Paste")
			(roundrect_rratio 0.2)
			(net 10 "/Power supply/VOUT4")
			(pintype "passive")
		)
	)
)
